FILE_TYPE = MULTI_PHYS_TABLE;

PART 'Q_FUSE'

{========================================================================================}
:PACK_TYPE | VALUE        | MATERIAL | PART_NUMBER              = ENVCOMP | PART_NUMBER              | JEDEC_TYPE     | CLASS | DESCRIPTION                                  | HEIGHT    | COMPONENT_TYPE | LEAD_LENGTH | LPID | DAY        ;
{========================================================================================}
 'SMLF'    | '1.1A'       | 'IC'     | 'TMP_QDK110TPU110'(!)    = 'YES'   | 'TMP_QDK110TPU110'       | 'F1812'      | 'IC'  | '1.1A'                                       | '.030 IN' | 'CHIP'         | ''          | ''   | ''        
 'SMLF'    | '1.1A'       | 'EMPTY'  | 'TMP_QDK110TPU110'(!)    = 'YES'   | 'TMP_QDK110TPU110'       | 'F1812'      | 'IO'  | '1.1A'                                       | '.030 IN' | 'CHIP'         | ''          | ''   | ''        
 'SMLF'    | '4.5A'       | 'IC'     | 'TMP_QDK450WFU004'(!)    = 'YES'   | 'TMP_QDK450WFU004'       | 'F1206'      | 'IC'  | '4.5A'                                       | '.044 IN' | 'CHIP'         | ''          | ''   | ''        
 'SMLF'    | '4.5A'       | 'EMPTY'  | 'TMP_QDK450WFU004'(!)    = 'YES'   | 'TMP_QDK450WFU004'       | 'F1206'      | 'IO'  | '4.5A'                                       | '.044 IN' | 'CHIP'         | ''          | ''   | ''        
 'SMLF'    | '3A'         | 'IC'     | 'TMP_QDK300UFU000'(!)    = 'YES'   | 'TMP_QDK300UFU000'       | 'F1206'      | 'IC'  | '3A'                                         | '.035 IN' | 'CHIP'         | ''          | ''   | ''        
 'SMLF'    | '3A'         | 'EMPTY'  | 'TMP_QDK300UFU000'(!)    = 'YES'   | 'TMP_QDK300UFU000'       | 'F1206'      | 'IO'  | '3A'                                         | '.035 IN' | 'CHIP'         | ''          | ''   | ''        
 'SMLF'    | '5A/32V'     | 'IC'     | 'TMP_QDK500WFU011'(!)    = 'YES'   | 'TMP_QDK500WFU011'       | 'F1206'      | 'IC'  | 'FUSE SMD 5A/ 32V/3216(FAST,UL/CSA)'         | '.035 IN' | 'CHIP'         | ''          | ''   | ''        
 'SMLF'    | '5A/32V'     | 'EMPTY'  | 'TMP_QDK500WFU011'(!)    = 'YES'   | 'TMP_QDK500WFU011'       | 'F1206'      | 'IO'  | 'FUSE SMD 5A/ 32V/3216(FAST,UL/CSA)'         | '.035 IN' | 'CHIP'         | ''          | ''   | ''        
 'SMLF'    | '1.5A/63V'   | 'IC'     | 'TMP-C_S2I_0911_MASON_1'(!) = 'YES'   | 'TMP-C_S2I_0911_MASON_1' | 'F1206'      | 'IC'  | 'FUSE SMD 1.5A 63V FAST(TR/3216FF1.5-R)'     | '.035 IN' | 'CHIP'         | ''          | ''   | ''        
 'SMLF'    | '1.5A/63V'   | 'EMPTY'  | 'TMP-C_S2I_0911_MASON_1'(!) = 'YES'   | 'TMP-C_S2I_0911_MASON_1' | 'F1206'      | 'IO'  | 'FUSE SMD 1.5A 63V FAST(TR/3216FF1.5-R)'     | '.035 IN' | 'CHIP'         | ''          | ''   | ''        
 'SMLF'    | '1.6A/9V'    | 'IC'     | 'TMP_QDK160TPU113'(!)    = 'YES'   | 'TMP_QDK160TPU113'       | 'F1812'      | 'IC'  | 'FUSE SMD 1.6A 9V POLY(MINISMDC160F-2)'      | '.019 IN' | 'CHIP'         | ''          | ''   | ''        
 'SMLF'    | '1.6A/9V'    | 'EMPTY'  | 'TMP_QDK160TPU113'(!)    = 'YES'   | 'TMP_QDK160TPU113'       | 'F1812'      | 'IO'  | 'FUSE SMD 1.6A 9V POLY(MINISMDC160F-2)'      | '.019 IN' | 'CHIP'         | ''          | ''   | ''        
 'SMLF'    | '1.5A/6V'    | 'IC'     | 'QN-DK150TPU030'(!)      = 'YES'   | 'DK150TPU030'         | 'F1206_H56'    | 'IC'  | 'FUSE SMD 1.5A,6V(POLY,NANOSMDC150F-2)'      | '.055 IN' | 'CHIP'         | ''          | ''   | ''        
 'SMLF'    | '1.5A/6V'    | 'EMPTY'  | 'QN-DK150TPU030'(!)      = 'YES'   | 'DK150TPU030'         | 'F1206_H56'    | 'IO'  | 'FUSE SMD 1.5A,6V(POLY,NANOSMDC150F-2)'      | '.055 IN' | 'CHIP'         | ''          | ''   | ''        
 'SMLF'    | '3A/6V'      | 'IC'     | 'TMP-C_S2I_0421_MASON_1'(!) = 'YES'   | 'TMP-C_S2I_0421_MASON_1' | 'F2920_3'    | 'IC'  | 'FUSE SMD 3A 6V POLY(SMD300F,UL/CSA)'        | '.118 IN' | 'CHIP'         | ''          | ''   | ''        
 'SMLF'    | '3A/6V'      | 'EMPTY'  | 'TMP-C_S2I_0421_MASON_1'(!) = 'YES'   | 'TMP-C_S2I_0421_MASON_1' | 'F2920_3'    | 'IO'  | 'FUSE SMD 3A 6V POLY(SMD300F,UL/CSA)'        | '.118 IN' | 'CHIP'         | ''          | ''   | ''        
 'SMLF'    | '1.5A/6V'    | 'IC'     | 'TMP-C_S2I_0422_MASON_1'(!) = 'YES'   | 'TMP-C_S2I_0422_MASON_1' | 'F1206'      | 'IC'  | 'FUSE SMD 1.5A 6V POLY(nanoSMDC150F,UL/CSA)' | '.035 IN' | 'CHIP'         | ''          | ''   | ''        
 'SMLF'    | '1.5A/6V'    | 'EMPTY'  | 'TMP-C_S2I_0422_MASON_1'(!) = 'YES'   | 'TMP-C_S2I_0422_MASON_1' | 'F1206'      | 'IO'  | 'FUSE SMD 1.5A 6V POLY(nanoSMDC150F,UL/CSA)' | '.035 IN' | 'CHIP'         | ''          | ''   | ''        
 'SMLF'    | '0.5A/13.2V' | 'IC'     | 'TMP_QDK050SPU017'(!)    = 'YES'   | 'TMP_QDK050SPU017'       | 'F1206'      | 'IC'  | 'FUSE SMD 0.5A,13.2V(POLY,NANOSMDC050F)'     | '.025 IN' | 'CHIP'         | ''          | ''   | ''        
 'SMLF'    | '0.5A/13.2V' | 'EMPTY'  | 'TMP_QDK050SPU017'(!)    = 'YES'   | 'TMP_QDK050SPU017'       | 'F1206'      | 'IO'  | 'FUSE SMD 0.5A,13.2V(POLY,NANOSMDC050F)'     | '.025 IN' | 'CHIP'         | ''          | ''   | ''        
 'SMLF'    | '3A/15V'     | 'IC'     | 'TMP-C_S2I_0427_MASON_1'(!) = 'YES'   | 'TMP-C_S2I_0427_MASON_1' | 'F2920_1-25' | 'IC'  | 'FUSE SMD 3A 15V POLY(2920L300/15)'          | '.050 IN' | 'CHIP'         | ''          | ''   | ''        
 'SMLF'    | '3A/15V'     | 'EMPTY'  | 'TMP-C_S2I_0427_MASON_1'(!) = 'YES'   | 'TMP-C_S2I_0427_MASON_1' | 'F2920_1-25' | 'IO'  | 'FUSE SMD 3A 15V POLY(2920L300/15)'          | '.050 IN' | 'CHIP'         | ''          | ''   | ''        
 'SMLF'    | '1.5A 32V'   | 'IC'     | 'TMP_QDK150WFU000'(!)    = 'YES'   | 'TMP_QDK150WFU000'       | 'F0603_H19'  | 'IC'  | 'FUSE SMD 1.5A 32V(FAST,UL/CSA,0603)'        | '.022 IN' | 'CHIP'         | ''          | ''   | ''        
 'SMLF'    | '1.5A 32V'   | 'EMPTY'  | 'TMP_QDK150WFU000'(!)    = 'YES'   | 'TMP_QDK150WFU000'       | 'F0603_H19'  | 'IO'  | 'FUSE SMD 1.5A 32V(FAST,UL/CSA,0603)'        | '.022 IN' | 'CHIP'         | ''          | ''   | ''        
 'SMLF'    | '6A,24V'     | 'IC'     | 'TMP_QDK600VPU004'(!)    = 'YES'   | 'TMP_QDK600VPU004'       | 'F1206'      | 'IC'  | 'FUSE SMD 6A,24V POLY(1206SFS600F/24-2)'     | '.046 IN' | 'CHIP'         | ''          | ''   | ''        
 'SMLF'    | '6A,24V'     | 'EMPTY'  | 'TMP_QDK600VPU004'(!)    = 'YES'   | 'TMP_QDK600VPU004'       | 'F1206'      | 'IO'  | 'FUSE SMD 6A,24V POLY(1206SFS600F/24-2)'     | '.046 IN' | 'CHIP'         | ''          | ''   | ''        
 'SMLF'    | '10A/125V'   | 'IC'     | 'TMP_QDKA00XFU409'(!)    = 'YES'   | 'TMP_QDKA00XFU409'       | 'F2410'      | 'IC'  | 'FUSE SMD 10A/125V(FAST,UL/CSA)'             | '.106 IN' | 'CHIP'         | ''          | ''   | ''        
 'SMLF'    | '10A/125V'   | 'EMPTY'  | 'TMP_QDKA00XFU409'(!)    = 'YES'   | 'TMP_QDKA00XFU409'       | 'F2410'      | 'IO'  | 'FUSE SMD 10A/125V(FAST,UL/CSA)'             | '.106 IN' | 'CHIP'         | ''          | ''   | ''        
 'SMLF'    | '.75A/13.2V' | 'IC'     | 'DK075SPU002'(!)         = 'YES'   | 'DK075SPU002'            | 'F1812'      | 'IC'  | 'FUSE SMD .75A,13.2V(POLY,MINISMDC075F)LF'   | '.019 IN' | 'CHIP'         | ''          | ''   | ''        
 'SMLF'    | '.75A/13.2V' | 'EMPTY'  | 'DK075SPU002'(!)         = 'YES'   | 'DK075SPU002'            | 'F1812'      | 'IO'  | 'FUSE SMD .75A,13.2V(POLY,MINISMDC075F)LF'   | '.019 IN' | 'CHIP'         | ''          | ''   | ''        
 'SMLF'    | '1.1A/16V'   | 'IC'     | 'DK110SPU001'(!)         = 'YES'   | 'DK110SPU001'            | 'F1812'      | 'IC'  | 'FUSE SMD 1.1A 16V POLY(MF-MSMF110/16)'      | '.019 IN' | 'CHIP'         | ''          | ''   | ''        
 'SMLF'    | '1.1A/16V'   | 'EMPTY'  | 'DK110SPU001'(!)         = 'YES'   | 'DK110SPU001'            | 'F1812'      | 'IO'  | 'FUSE SMD 1.1A 16V POLY(MF-MSMF110/16)'      | '.019 IN' | 'CHIP'         | ''          | ''   | ''        
 'SMLF'    | '3A/15V'     | 'IC'     | 'DK300SPU002'(!)         = 'YES'   | 'DK300SPU002'            | 'F2920_3'    | 'IC'  | 'FUSE SMD 3A,15V,POLY(SMD300F/15)'           | '.118 IN' | 'CHIP'         | ''          | ''   | ''        
 'SMLF'    | '3A/15V'     | 'EMPTY'  | 'DK300SPU002'(!)         = 'YES'   | 'DK300SPU002'            | 'F2920_3'    | 'IO'  | 'FUSE SMD 3A,15V,POLY(SMD300F/15)'           | '.118 IN' | 'CHIP'         | ''          | ''   | ''        
 'SMLF'    | '1.1A/8V'    | 'IC'     | 'DK110TPU012'(!)         = 'YES'   | 'DK110TPU012'            | 'F1812'      | 'IC'  | 'FUSE SMD 1.1A,8V(POLY,MINISMDC110F-2)'      | '.025 IN' | 'CHIP'         | ''          | ''   | '20101005'
 'SMLF'    | '1.1A/8V'    | 'EMPTY'  | 'DK110TPU012'(!)         = 'YES'   | 'DK110TPU012'            | 'F1812'      | 'IO'  | 'FUSE SMD 1.1A,8V(POLY,MINISMDC110F-2)'      | '.025 IN' | 'CHIP'         | ''          | ''   | '20101005'
 'SMLF'    | '1.5A/6V'    | 'IC'     | 'DK150TPU072'(!)         = 'YES'   | 'DK150TPU072'            | 'F1206'      | 'IC'  | 'FUSE SMD 1.5A,6V(POLY,1206L150PR)'          | '.025 IN' | 'CHIP'         | ''          | ''   | '20110207'
 'SMLF'    | '1.5A/6V'    | 'EMPTY'  | 'DK150TPU072'(!)         = 'YES'   | 'DK150TPU072'            | 'F1206'      | 'IO'  | 'FUSE SMD 1.5A,6V(POLY,1206L150PR)'          | '.025 IN' | 'CHIP'         | ''          | ''   | '20110207'
 'SMLF'    | '1.1A/6V'    | 'IC'     | 'DK110TPU501'(!)         = 'YES'   | 'DK110TPU501'            | 'F1206'      | 'IC'  | 'FUSE SMD 1.1A6V POLY(NANOSMDC110F-2)1206'   | '.025 IN' | 'CHIP'         | ''          | ''   | '20110217'
 'SMLF'    | '1.1A/6V'    | 'EMPTY'  | 'DK110TPU501'(!)         = 'YES'   | 'DK110TPU501'            | 'F1206'      | 'IO'  | 'FUSE SMD 1.1A6V POLY(NANOSMDC110F-2)1206'   | '.025 IN' | 'CHIP'         | ''          | ''   | '20110217'
 'SMLF'    | '5A/125V'    | 'IC'     | 'DK500XFU001'(!)         = 'YES'   | 'DK500XFU001'            | 'F2410'      | 'IC'  | 'FUSE SMD 5A/125V(FAST,UL/CSA)0451005.MRL'   | '.106 IN' | 'CHIP'         | ''          | ''   | '20120224'
 'SMLF'    | '5A/125V'    | 'EMPTY'  | 'DK500XFU001'(!)         = 'YES'   | 'DK500XFU001'            | 'F2410'      | 'IO'  | 'FUSE SMD 5A/125V(FAST,UL/CSA)0451005.MRL'   | '.106 IN' | 'CHIP'         | ''          | ''   | '20120224'
 'SMLF'    | '3A/15V'     | 'IC'     | 'DK300SPU000'(!)         = 'YES'   | 'DK300SPU000'            | 'F2920_1-25' | 'IC'  | 'FUSE SMD 3A 15V POLY(2920L300/15DR)'        | '.050 IN' | 'CHIP'         | ''          | ''   | '20120306'
 'SMLF'    | '3A/15V'     | 'EMPTY'  | 'DK300SPU000'(!)         = 'YES'   | 'DK300SPU000'            | 'F2920_1-25' | 'IO'  | 'FUSE SMD 3A 15V POLY(2920L300/15DR)'        | '.050 IN' | 'CHIP'         | ''          | ''   | '20120306'
 'SMLF'    | '15A/125V'   | 'IC'     | 'DKF00VFU004'(!) = 'YES'   | 'DKF00VFU004'  | 'F2410'      | 'IC'  | 'FUSE SMD 15A/125V(FAST,UL/CSA)SSQ 15'       | '.106 IN' | 'CHIP'         | ''          | ''   | '20120309'
 'SMLF'    | '15A/125V'   | 'EMPTY'  | 'DKF00VFU004'(!) = 'YES'   | 'DKF00VFU004'  | 'F2410'      | 'IO'  | 'FUSE SMD 15A/125V(FAST,UL/CSA)SSQ 15'       | '.106 IN' | 'CHIP'         | ''          | ''   | '20120309'
 'SMLF'     | '1.5A/125V'  | 'IC'     | 'DK150XFU000'(!)           = 'YES'   | 'DK150XFU000'              | 'F2410'           | 'IC'  | 'FUSE SMD 1.5A/125V(FAST,UL/CSA/CE)SSQ1.5'   | '.100 IN'  | 'CHIP'         | ''          | ''   | '20120406'
 'SMLF'     | '1.5A/125V'  | 'EMPTY'  | 'DK150XFU000'(!)           = 'YES'   | 'DK150XFU000'              | 'F2410'           | 'IO'  | 'FUSE SMD 1.5A/125V(FAST,UL/CSA/CE)SSQ1.5'   | '.100 IN'  | 'CHIP'         | ''          | ''   | '20120406'
 'SMLF'     | '2A/6V'      | 'IC'     | 'DK200TPU004'(!)           = 'YES'   | 'DK200TPU004'              | 'F1206'           | 'IC'  | 'FUSE SMD 2A 6V(POLY,UL/CSA,1206)'           | '.063 IN'  | 'CHIP'         | ''          | ''   | '20120421'
 'SMLF'     | '2A/6V'      | 'EMPTY'  | 'DK200TPU004'(!)           = 'YES'   | 'DK200TPU004'              | 'F1206'           | 'IO'  | 'FUSE SMD 2A 6V(POLY,UL/CSA,1206)'           | '.063  IN' | 'CHIP'         | ''          | ''   | '20120421'
 'THLF'    | '9A/16V'     | 'IC'     | 'DK900SPU001'(!) = 'YES'   | 'DK900SPU001'    | 'F1255_16R900GMR'   | 'IC'  | 'FUSE DIP 9A/16V (POLY,UL/TUV)16R900GMR'     | '.855 IN'  | 'CHIP'         | ''          | ''   | '20120314'
 'THLF'    | '9A/16V'     | 'EMPTY'  | 'DK900SPU001'(!) = 'YES'   | 'DK900SPU001'    | 'F1255_16R900GMR'   | 'IO'  | 'FUSE DIP 9A/16V (POLY,UL/TUV)16R900GMR'     | '.855 IN'  | 'CHIP'         | ''          | ''   | '20120314'
 'THLF'    | '14A/16V'    | 'IC'     | 'DKE00SPU000'(!) = 'YES'   | 'DKE00SPU000'    | 'F9314_16R1400GH'   | 'IC'  | 'FUSE DIP 14A/16V(POLY,UL/TUV)16R1400GH'     | '1.099 IN' | 'CHIP'         | ''          | ''   | '20120314'
 'THLF'    | '14A/16V'    | 'EMPTY'  | 'DKE00SPU000'(!) = 'YES'   | 'DKE00SPU000'    | 'F9314_16R1400GH'   | 'IO'  | 'FUSE DIP 14A/16V(POLY,UL/TUV)16R1400GH'     | '1.099 IN' | 'CHIP'         | ''          | ''   | '20120314'
 'THLF_SEL'    | '9A/16V'     | 'IC'     | 'SP_DK900SPU001'(!) = 'YES'   | 'SP_DK900SPU001' | 'G_F1255_16R900GMR' | 'IC'  | 'FUSE DIP 9A/16V (POLY,UL/TUV)16R900GMR'     | '.855 IN'  | 'CHIP'         | ''          | ''   | '20120314'
 'THLF_SEL'    | '9A/16V'     | 'EMPTY'  | 'SP_DK900SPU001'(!) = 'YES'   | 'SP_DK900SPU001' | 'G_F1255_16R900GMR' | 'IO'  | 'FUSE DIP 9A/16V (POLY,UL/TUV)16R900GMR'     | '.855 IN'  | 'CHIP'         | ''          | ''   | '20120314'
 'THLF_SEL'    | '14A/16V'    | 'IC'     | 'SP_DKE00SPU000'(!) = 'YES'   | 'SP_DKE00SPU000' | 'G_F9314_16R1400GH' | 'IC'  | 'FUSE DIP 14A/16V(POLY,UL/TUV)16R1400GH'     | '1.099 IN' | 'CHIP'         | ''          | ''   | '20120314'
 'THLF_SEL'    | '14A/16V'    | 'EMPTY'  | 'SP_DKE00SPU000'(!) = 'YES'   | 'SP_DKE00SPU000' | 'G_F9314_16R1400GH' | 'IO'  | 'FUSE DIP 14A/16V(POLY,UL/TUV)16R1400GH'     | '1.099 IN' | 'CHIP'         | ''          | ''   | '20120314'
 'SMLF'     | '0.5A'       | 'IC'     | 'DK050SPU033'(!)         = 'YES'   | 'DK050SPU033'            | 'F1812'           | 'IC'  | 'FUSE SMD 0.5A 15V POLY(SMD1812P050TF)'      | '.019IN'   | 'CHIP'         | ''          | ''   | '20120525'
 'SMLF'     | '0.5A'       | 'EMPTY'  | 'DK050SPU033'(!)         = 'YES'   | 'DK050SPU033'            | 'F1812'           | 'IO'  | 'FUSE SMD 0.5A 15V POLY(SMD1812P050TF)'      | '.019IN'   | 'CHIP'         | ''          | ''   | '20120525'
 'SMLF'     | '2.6A'       | 'IC'     | 'DK260TPU001'(!)         = 'YES'   | 'DK260TPU001'            | 'F1812'           | 'IC'  | 'FUSE SMD 2.6A,6V(POLY,MINISMDC260F)'        | '.019IN'   | 'CHIP'         | ''          | ''   | '20120627'
 'SMLF'     | '2.6A'       | 'EMPTY'  | 'DK260TPU001'(!)         = 'YES'   | 'DK260TPU001'            | 'F1812'           | 'IO'  | 'FUSE SMD 2.6A,6V(POLY,MINISMDC260F)'        | '.019IN'   | 'CHIP'         | ''          | ''   | '20120627'
 'SMLF'     | '8A/32V'     | 'IC'     | 'DK800WFU000'(!)         = 'YES'   | 'DK800WFU000'            | 'F1206'             | 'IC'  | 'FUSE SMD 8A 32V(FAST,0437008.WR,1206)'      | '.033IN'   | 'CHIP'         | ''          | ''   | '20120628'
 'SMLF'     | '8A/32V'     | 'EMPTY'  | 'DK800WFU000'(!)         = 'YES'   | 'DK800WFU000'            | 'F1206'             | 'IO'  | 'FUSE SMD 8A 32V(FAST,0437008.WR,1206)'      | '.033IN'   | 'CHIP'         | ''          | ''   | '20120628'
 'SMLF'     | '3A/24V'     | 'IC'     | 'DK300VPU000'(!)         = 'YES'   | 'DK300VPU000'            | 'F2920_1-6'       | 'IC'  | 'FUSE SMD 3A 24V POLY(MF-LSMF300/24X-2)'     | '.063IN'   | 'CHIP'         | ''          | ''   | '20120706'
 'SMLF'     | '3A/24V'     | 'EMPTY'  | 'DK300VPU000'(!)         = 'YES'   | 'DK300VPU000'            | 'F2920_1-6'       | 'IO'  | 'FUSE SMD 3A 24V POLY(MF-LSMF300/24X-2)'     | '.063IN'   | 'CHIP'         | ''          | ''   | '20120706'
 'SMLF'     | '0.35A/6V'   | 'IC'     | 'DK035TPU000'(!)         = ''       | ''        | 'DK035TPU000'            | 'F0603_H62'       | 'IC'  | 'FUSE SMD 0.35A.6V(POLY.SMD0603P035TF)'      | 'CHIP'         | ''          | ''   | '20120914'
 'SMLF'     | '0.35A/6V'   | 'EMPTY'  | 'DK035TPU000'(!)         = ''       | ''        | 'DK035TPU000'            | 'F0603_H62'       | 'IO'  | 'FUSE SMD 0.35A.6V(POLY.SMD0603P035TF)'      | 'CHIP'         | ''          | ''   | '20120914'

END_PART

END.

